(kicad_pcb
	(version 20241229)
	(generator "pcbnew")
	(generator_version "9.0")
	(general
		(thickness 1.599998)
		(legacy_teardrops no)
	)
	(paper "A4")
	(title_block
		(date "2023-02-12")
		(rev "1.1.5")
		(comment 9 "footprints 275-280 of 473")
	)
	(layers
		(0 "F.Cu" signal)
		(4 "In1.Cu" power "In1.GND")
		(6 "In2.Cu" signal)
		(8 "In3.Cu" power "In3.GND")
		(10 "In4.Cu" power "In4.VCC")
		(12 "In5.Cu" signal)
		(14 "In6.Cu" power "In6.VCC")
		(2 "B.Cu" signal)
		(9 "F.Adhes" user "F.Adhesive")
		(11 "B.Adhes" user "B.Adhesive")
		(13 "F.Paste" user)
		(15 "B.Paste" user)
		(5 "F.SilkS" user "F.Silkscreen")
		(7 "B.SilkS" user "B.Silkscreen")
		(1 "F.Mask" user)
		(3 "B.Mask" user)
		(17 "Dwgs.User" user "User.Drawings")
		(19 "Cmts.User" user "User.Comments")
		(21 "Eco1.User" user "User.Eco1")
		(23 "Eco2.User" user "User.Eco2")
		(25 "Edge.Cuts" user)
		(27 "Margin" user)
		(31 "F.CrtYd" user "F.Courtyard")
		(29 "B.CrtYd" user "B.Courtyard")
		(35 "F.Fab" user)
		(33 "B.Fab" user)
	)
	(footprint "antmicro-footprints:C_0603_1608Metric"
		(layer "F.Cu")
		(at 128.6 66.8 180)
		(descr "Capacitor SMD 0603")
		(tags "capacitor 0603")
		(property "Reference" "C189"
			(at 3.9 -0.4 180)
			(layer "F.SilkS")
			(effects
				(font
					(size 0.7 0.7)
					(thickness 0.15)
				)
				(justify left bottom)
			)
		)
		(property "Value" "C_22u_0603"
			(at 0 1.6 180)
			(layer "F.Fab")
			(effects
				(font
					(size 0.7 0.7)
					(thickness 0.15)
				)
				(justify left bottom)
			)
		)
		(property "Description" " "
			(at 0 0 180)
			(layer "F.Fab")
			(hide yes)
			(effects
				(font
					(size 1.27 1.27)
					(thickness 0.15)
				)
			)
		)
		(property "Author" "Antmicro"
			(at 257.2 133.6 0)
			(layer "F.Fab")
			(hide yes)
			(effects
				(font
					(size 1 1)
					(thickness 0.15)
				)
			)
		)
		(property "Dielectric" ""
			(at 257.2 133.6 0)
			(layer "F.Fab")
			(hide yes)
			(effects
				(font
					(size 1 1)
					(thickness 0.15)
				)
			)
		)
		(property "License" "Apache-2.0"
			(at 257.2 133.6 0)
			(layer "F.Fab")
			(hide yes)
			(effects
				(font
					(size 1 1)
					(thickness 0.15)
				)
			)
		)
		(property "MPN" "GRM188R60J226MEA0D"
			(at 257.2 133.6 0)
			(layer "F.Fab")
			(hide yes)
			(effects
				(font
					(size 1 1)
					(thickness 0.15)
				)
			)
		)
		(property "Manufacturer" "Murata"
			(at 257.2 133.6 0)
			(layer "F.Fab")
			(hide yes)
			(effects
				(font
					(size 1 1)
					(thickness 0.15)
				)
			)
		)
		(property "Val" "22u"
			(at 257.2 133.6 0)
			(layer "F.Fab")
			(hide yes)
			(effects
				(font
					(size 1 1)
					(thickness 0.15)
				)
			)
		)
		(property "Voltage" ""
			(at 257.2 133.6 0)
			(layer "F.Fab")
			(hide yes)
			(effects
				(font
					(size 1 1)
					(thickness 0.15)
				)
			)
		)
		(sheetname "Supply")
		(sheetfile "supply.kicad_sch")
		(attr exclude_from_pos_files exclude_from_bom dnp)
		(fp_line
			(start -0.3 0.3)
			(end 0.3 0.3)
			(stroke
				(width 0.15)
				(type solid)
			)
			(layer "F.SilkS")
		)
		(fp_line
			(start -0.3 -0.3)
			(end 0.3 -0.3)
			(stroke
				(width 0.15)
				(type solid)
			)
			(layer "F.SilkS")
		)
		(fp_rect
			(start -1.24 -0.7)
			(end 1.24 0.7)
			(stroke
				(width 0.05)
				(type solid)
			)
			(fill no)
			(layer "F.CrtYd")
		)
		(fp_rect
			(start -0.8 -0.4)
			(end 0.8 0.4)
			(stroke
				(width 0.15)
				(type solid)
			)
			(fill no)
			(layer "F.Fab")
		)
		(pad "1" smd roundrect
			(at -0.7 0 180)
			(size 0.6 0.8)
			(layers "F.Cu" "F.Mask" "F.Paste")
			(roundrect_rratio 0.2)
			(net 551 "/Supply/VDD1V8")
			(pintype "passive")
		)
		(pad "2" smd roundrect
			(at 0.7 0 180)
			(size 0.6 0.8)
			(layers "F.Cu" "F.Mask" "F.Paste")
			(roundrect_rratio 0.2)
			(net 5 "GND")
			(pintype "passive")
		)
	)
	(footprint "antmicro-footprints:C_0603_1608Metric"
		(layer "F.Cu")
		(at 136.7 54.9)
		(descr "Capacitor SMD 0603")
		(tags "capacitor 0603")
		(property "Reference" "C198"
			(at 1 0.4 0)
			(layer "F.SilkS")
			(effects
				(font
					(size 0.7 0.7)
					(thickness 0.15)
				)
				(justify left bottom)
			)
		)
		(property "Value" "C_22u_0603"
			(at 0 1.6 0)
			(layer "F.Fab")
			(effects
				(font
					(size 0.7 0.7)
					(thickness 0.15)
				)
				(justify left bottom)
			)
		)
		(property "Description" " "
			(at 0 0 0)
			(layer "F.Fab")
			(hide yes)
			(effects
				(font
					(size 1.27 1.27)
					(thickness 0.15)
				)
			)
		)
		(property "Author" "Antmicro"
			(at 0 0 0)
			(layer "F.Fab")
			(hide yes)
			(effects
				(font
					(size 1 1)
					(thickness 0.15)
				)
			)
		)
		(property "Dielectric" ""
			(at 0 0 0)
			(layer "F.Fab")
			(hide yes)
			(effects
				(font
					(size 1 1)
					(thickness 0.15)
				)
			)
		)
		(property "License" "Apache-2.0"
			(at 0 0 0)
			(layer "F.Fab")
			(hide yes)
			(effects
				(font
					(size 1 1)
					(thickness 0.15)
				)
			)
		)
		(property "MPN" "GRM188R60J226MEA0D"
			(at 0 0 0)
			(layer "F.Fab")
			(hide yes)
			(effects
				(font
					(size 1 1)
					(thickness 0.15)
				)
			)
		)
		(property "Manufacturer" "Murata"
			(at 0 0 0)
			(layer "F.Fab")
			(hide yes)
			(effects
				(font
					(size 1 1)
					(thickness 0.15)
				)
			)
		)
		(property "Val" "22u"
			(at 0 0 0)
			(layer "F.Fab")
			(hide yes)
			(effects
				(font
					(size 1 1)
					(thickness 0.15)
				)
			)
		)
		(property "Voltage" ""
			(at 0 0 0)
			(layer "F.Fab")
			(hide yes)
			(effects
				(font
					(size 1 1)
					(thickness 0.15)
				)
			)
		)
		(sheetname "Supply")
		(sheetfile "supply.kicad_sch")
		(attr exclude_from_pos_files exclude_from_bom dnp)
		(fp_line
			(start -0.3 -0.3)
			(end 0.3 -0.3)
			(stroke
				(width 0.15)
				(type solid)
			)
			(layer "F.SilkS")
		)
		(fp_line
			(start -0.3 0.3)
			(end 0.3 0.3)
			(stroke
				(width 0.15)
				(type solid)
			)
			(layer "F.SilkS")
		)
		(fp_rect
			(start -1.24 -0.7)
			(end 1.24 0.7)
			(stroke
				(width 0.05)
				(type solid)
			)
			(fill no)
			(layer "F.CrtYd")
		)
		(fp_rect
			(start -0.8 -0.4)
			(end 0.8 0.4)
			(stroke
				(width 0.15)
				(type solid)
			)
			(fill no)
			(layer "F.Fab")
		)
		(pad "1" smd roundrect
			(at -0.7 0)
			(size 0.6 0.8)
			(layers "F.Cu" "F.Mask" "F.Paste")
			(roundrect_rratio 0.2)
			(net 550 "VDD1V1")
			(pintype "passive")
		)
		(pad "2" smd roundrect
			(at 0.7 0)
			(size 0.6 0.8)
			(layers "F.Cu" "F.Mask" "F.Paste")
			(roundrect_rratio 0.2)
			(net 5 "GND")
			(pintype "passive")
		)
	)
	(footprint "antmicro-footprints:C_0603_1608Metric"
		(layer "F.Cu")
		(at 128.925 52.725 90)
		(descr "Capacitor SMD 0603")
		(tags "capacitor 0603")
		(property "Reference" "C195"
			(at 1.025 0.275 90)
			(layer "F.SilkS")
			(effects
				(font
					(size 0.7 0.7)
					(thickness 0.15)
				)
				(justify left bottom)
			)
		)
		(property "Value" "C_22u_0603"
			(at 0 1.6 90)
			(layer "F.Fab")
			(effects
				(font
					(size 0.7 0.7)
					(thickness 0.15)
				)
				(justify left bottom)
			)
		)
		(property "Description" " "
			(at 0 0 90)
			(layer "F.Fab")
			(hide yes)
			(effects
				(font
					(size 1.27 1.27)
					(thickness 0.15)
				)
			)
		)
		(property "Author" "Antmicro"
			(at 181.65 -76.2 0)
			(layer "F.Fab")
			(hide yes)
			(effects
				(font
					(size 1 1)
					(thickness 0.15)
				)
			)
		)
		(property "Dielectric" ""
			(at 181.65 -76.2 0)
			(layer "F.Fab")
			(hide yes)
			(effects
				(font
					(size 1 1)
					(thickness 0.15)
				)
			)
		)
		(property "License" "Apache-2.0"
			(at 181.65 -76.2 0)
			(layer "F.Fab")
			(hide yes)
			(effects
				(font
					(size 1 1)
					(thickness 0.15)
				)
			)
		)
		(property "MPN" "GRM188R60J226MEA0D"
			(at 181.65 -76.2 0)
			(layer "F.Fab")
			(hide yes)
			(effects
				(font
					(size 1 1)
					(thickness 0.15)
				)
			)
		)
		(property "Manufacturer" "Murata"
			(at 181.65 -76.2 0)
			(layer "F.Fab")
			(hide yes)
			(effects
				(font
					(size 1 1)
					(thickness 0.15)
				)
			)
		)
		(property "Val" "22u"
			(at 181.65 -76.2 0)
			(layer "F.Fab")
			(hide yes)
			(effects
				(font
					(size 1 1)
					(thickness 0.15)
				)
			)
		)
		(property "Voltage" ""
			(at 181.65 -76.2 0)
			(layer "F.Fab")
			(hide yes)
			(effects
				(font
					(size 1 1)
					(thickness 0.15)
				)
			)
		)
		(sheetname "Supply")
		(sheetfile "supply.kicad_sch")
		(attr exclude_from_pos_files exclude_from_bom dnp)
		(fp_line
			(start -0.3 -0.3)
			(end 0.3 -0.3)
			(stroke
				(width 0.15)
				(type solid)
			)
			(layer "F.SilkS")
		)
		(fp_line
			(start -0.3 0.3)
			(end 0.3 0.3)
			(stroke
				(width 0.15)
				(type solid)
			)
			(layer "F.SilkS")
		)
		(fp_rect
			(start -1.24 -0.7)
			(end 1.24 0.7)
			(stroke
				(width 0.05)
				(type solid)
			)
			(fill no)
			(layer "F.CrtYd")
		)
		(fp_rect
			(start -0.8 -0.4)
			(end 0.8 0.4)
			(stroke
				(width 0.15)
				(type solid)
			)
			(fill no)
			(layer "F.Fab")
		)
		(pad "1" smd roundrect
			(at -0.7 0 90)
			(size 0.6 0.8)
			(layers "F.Cu" "F.Mask" "F.Paste")
			(roundrect_rratio 0.2)
			(net 550 "VDD1V1")
			(pintype "passive")
		)
		(pad "2" smd roundrect
			(at 0.7 0 90)
			(size 0.6 0.8)
			(layers "F.Cu" "F.Mask" "F.Paste")
			(roundrect_rratio 0.2)
			(net 5 "GND")
			(pintype "passive")
		)
	)
	(footprint "antmicro-footprints:C_0402_1005Metric"
		(layer "F.Cu")
		(at 111.147806 85.774 180)
		(descr "Capacitor SMD 0402")
		(tags "capacitor SMD 0402")
		(property "Reference" "C173"
			(at 3.647806 -0.326 180)
			(layer "F.SilkS")
			(effects
				(font
					(size 0.7 0.7)
					(thickness 0.15)
				)
				(justify left bottom)
			)
		)
		(property "Value" "C_22u_0402"
			(at 0 1.4 180)
			(layer "F.Fab")
			(effects
				(font
					(size 0.7 0.7)
					(thickness 0.15)
				)
				(justify left bottom)
			)
		)
		(property "Description" " "
			(at 0 0 180)
			(layer "F.Fab")
			(hide yes)
			(effects
				(font
					(size 1.27 1.27)
					(thickness 0.15)
				)
			)
		)
		(property "Author" "Antmicro"
			(at 222.295612 171.548 0)
			(layer "F.Fab")
			(hide yes)
			(effects
				(font
					(size 1 1)
					(thickness 0.15)
				)
			)
		)
		(property "Dielectric" ""
			(at 222.295612 171.548 0)
			(layer "F.Fab")
			(hide yes)
			(effects
				(font
					(size 1 1)
					(thickness 0.15)
				)
			)
		)
		(property "License" "Apache-2.0"
			(at 222.295612 171.548 0)
			(layer "F.Fab")
			(hide yes)
			(effects
				(font
					(size 1 1)
					(thickness 0.15)
				)
			)
		)
		(property "MPN" "04024W226MAT2A"
			(at 222.295612 171.548 0)
			(layer "F.Fab")
			(hide yes)
			(effects
				(font
					(size 1 1)
					(thickness 0.15)
				)
			)
		)
		(property "Manufacturer" "AVX"
			(at 222.295612 171.548 0)
			(layer "F.Fab")
			(hide yes)
			(effects
				(font
					(size 1 1)
					(thickness 0.15)
				)
			)
		)
		(property "Val" "22u"
			(at 222.295612 171.548 0)
			(layer "F.Fab")
			(hide yes)
			(effects
				(font
					(size 1 1)
					(thickness 0.15)
				)
			)
		)
		(property "Voltage" ""
			(at 222.295612 171.548 0)
			(layer "F.Fab")
			(hide yes)
			(effects
				(font
					(size 1 1)
					(thickness 0.15)
				)
			)
		)
		(sheetname "Supply")
		(sheetfile "supply.kicad_sch")
		(attr smd)
		(fp_rect
			(start -0.94 -0.47)
			(end 0.94 0.47)
			(stroke
				(width 0.05)
				(type solid)
			)
			(fill no)
			(layer "F.CrtYd")
		)
		(fp_rect
			(start -0.499 -0.249)
			(end 0.499 0.249)
			(stroke
				(width 0.15)
				(type solid)
			)
			(fill no)
			(layer "F.Fab")
		)
		(pad "1" smd roundrect
			(at -0.484 0 180)
			(size 0.59 0.64)
			(layers "F.Cu" "F.Mask" "F.Paste")
			(roundrect_rratio 0.25)
			(net 583 "/Supply/1V8_REG")
			(pintype "passive")
		)
		(pad "2" smd roundrect
			(at 0.484 0 180)
			(size 0.59 0.64)
			(layers "F.Cu" "F.Mask" "F.Paste")
			(roundrect_rratio 0.25)
			(net 5 "GND")
			(pintype "passive")
		)
	)
	(footprint "antmicro-footprints:R_0402_1005Metric"
		(layer "F.Cu")
		(at 118.275 100.549 180)
		(descr "Resistor SMD 0402")
		(tags "resistor SMD 0402")
		(property "Reference" "R128"
			(at 0.875 2.549 180)
			(layer "F.SilkS")
			(effects
				(font
					(size 0.7 0.7)
					(thickness 0.15)
				)
				(justify left bottom)
			)
		)
		(property "Value" "R_0R_0402"
			(at 0 1.4 180)
			(layer "F.Fab")
			(effects
				(font
					(size 0.7 0.7)
					(thickness 0.15)
				)
				(justify left bottom)
			)
		)
		(property "Description" "0R resistor in 0402 package with unspecified tolerance"
			(at 0 0 180)
			(layer "F.Fab")
			(hide yes)
			(effects
				(font
					(size 1.27 1.27)
					(thickness 0.15)
				)
			)
		)
		(property "Author" "Antmicro"
			(at 236.55 201.098 0)
			(layer "F.Fab")
			(hide yes)
			(effects
				(font
					(size 1 1)
					(thickness 0.15)
				)
			)
		)
		(property "Current" "1A"
			(at 236.55 201.098 0)
			(layer "F.Fab")
			(hide yes)
			(effects
				(font
					(size 1 1)
					(thickness 0.15)
				)
			)
		)
		(property "License" "Apache-2.0"
			(at 236.55 201.098 0)
			(layer "F.Fab")
			(hide yes)
			(effects
				(font
					(size 1 1)
					(thickness 0.15)
				)
			)
		)
		(property "MPN" "ERJ2GE0R00X"
			(at 236.55 201.098 0)
			(layer "F.Fab")
			(hide yes)
			(effects
				(font
					(size 1 1)
					(thickness 0.15)
				)
			)
		)
		(property "Manufacturer" "Panasonic"
			(at 236.55 201.098 0)
			(layer "F.Fab")
			(hide yes)
			(effects
				(font
					(size 1 1)
					(thickness 0.15)
				)
			)
		)
		(property "Tolerance" ""
			(at 236.55 201.098 0)
			(layer "F.Fab")
			(hide yes)
			(effects
				(font
					(size 1 1)
					(thickness 0.15)
				)
			)
		)
		(property "Val" "0R"
			(at 236.55 201.098 0)
			(layer "F.Fab")
			(hide yes)
			(effects
				(font
					(size 1 1)
					(thickness 0.15)
				)
			)
		)
		(sheetname "Supply")
		(sheetfile "supply.kicad_sch")
		(attr smd)
		(fp_rect
			(start -0.93 -0.47)
			(end 0.93 0.47)
			(stroke
				(width 0.05)
				(type solid)
			)
			(fill no)
			(layer "F.CrtYd")
		)
		(fp_rect
			(start -0.5 -0.25)
			(end 0.5 0.25)
			(stroke
				(width 0.15)
				(type solid)
			)
			(fill no)
			(layer "F.Fab")
		)
		(pad "1" smd roundrect
			(at -0.485 0 180)
			(size 0.59 0.64)
			(layers "F.Cu" "F.Mask" "F.Paste")
			(roundrect_rratio 0.25)
			(net 5 "GND")
			(pintype "passive")
		)
		(pad "2" smd roundrect
			(at 0.485 0 180)
			(size 0.59 0.64)
			(layers "F.Cu" "F.Mask" "F.Paste")
			(roundrect_rratio 0.25)
			(net 617 "/Supply/3V3_MODE")
			(pintype "passive")
		)
	)
	(footprint "antmicro-footprints:C_Pol_EIA-A"
		(layer "F.Cu")
		(at 151.84 84.21 180)
		(descr "Capacitor SMD KEMET_A")
		(tags "capacitor SMD KEMET_A")
		(property "Reference" "C86"
			(at 1.04 1.01 180)
			(layer "F.SilkS")
			(effects
				(font
					(size 0.7 0.7)
					(thickness 0.15)
				)
				(justify left bottom)
			)
		)
		(property "Value" "C_100u_KEMET_A"
			(at 0 2 180)
			(layer "F.Fab")
			(effects
				(font
					(size 0.7 0.7)
					(thickness 0.15)
				)
				(justify left bottom)
			)
		)
		(property "Description" " "
			(at 0 0 180)
			(layer "F.Fab")
			(hide yes)
			(effects
				(font
					(size 1.27 1.27)
					(thickness 0.15)
				)
			)
		)
		(property "Author" "Antmicro"
			(at 303.68 168.42 0)
			(layer "F.Fab")
			(hide yes)
			(effects
				(font
					(size 1 1)
					(thickness 0.15)
				)
			)
		)
		(property "Dielectric" ""
			(at 303.68 168.42 0)
			(layer "F.Fab")
			(hide yes)
			(effects
				(font
					(size 1 1)
					(thickness 0.15)
				)
			)
		)
		(property "License" "Apache-2.0"
			(at 303.68 168.42 0)
			(layer "F.Fab")
			(hide yes)
			(effects
				(font
					(size 1 1)
					(thickness 0.15)
				)
			)
		)
		(property "MPN" "298D107X06R3A2T"
			(at 303.68 168.42 0)
			(layer "F.Fab")
			(hide yes)
			(effects
				(font
					(size 1 1)
					(thickness 0.15)
				)
			)
		)
		(property "Manufacturer" "Vishay"
			(at 303.68 168.42 0)
			(layer "F.Fab")
			(hide yes)
			(effects
				(font
					(size 1 1)
					(thickness 0.15)
				)
			)
		)
		(property "Val" "100u"
			(at 303.68 168.42 0)
			(layer "F.Fab")
			(hide yes)
			(effects
				(font
					(size 1 1)
					(thickness 0.15)
				)
			)
		)
		(property "Voltage" ""
			(at 303.68 168.42 0)
			(layer "F.Fab")
			(hide yes)
			(effects
				(font
					(size 1 1)
					(thickness 0.15)
				)
			)
		)
		(sheetname "FPGA power")
		(sheetfile "fpga-power.kicad_sch")
		(attr smd)
		(fp_line
			(start 1.5 0.85)
			(end 1.2 0.85)
			(stroke
				(width 0.12)
				(type solid)
			)
			(layer "F.SilkS")
		)
		(fp_line
			(start 1.5 0.7)
			(end 1.5 0.85)
			(stroke
				(width 0.12)
				(type solid)
			)
			(layer "F.SilkS")
		)
		(fp_line
			(start 1.5 -0.7)
			(end 1.5 -0.85)
			(stroke
				(width 0.12)
				(type solid)
			)
			(layer "F.SilkS")
		)
		(fp_line
			(start 1.5 -0.85)
			(end 1.2 -0.85)
			(stroke
				(width 0.12)
				(type solid)
			)
			(layer "F.SilkS")
		)
		(fp_line
			(start -1.5 0.85)
			(end -1.2 0.85)
			(stroke
				(width 0.12)
				(type solid)
			)
			(layer "F.SilkS")
		)
		(fp_line
			(start -1.5 0.7)
			(end -1.5 0.85)
			(stroke
				(width 0.12)
				(type solid)
			)
			(layer "F.SilkS")
		)
		(fp_line
			(start -1.5 -0.7)
			(end -1.5 -0.85)
			(stroke
				(width 0.12)
				(type solid)
			)
			(layer "F.SilkS")
		)
		(fp_line
			(start -1.5 -0.85)
			(end -1.2 -0.85)
			(stroke
				(width 0.12)
				(type solid)
			)
			(layer "F.SilkS")
		)
		(fp_line
			(start -1.775 -0.975)
			(end -1.775 -0.675)
			(stroke
				(width 0.12)
				(type solid)
			)
			(layer "F.SilkS")
		)
		(fp_line
			(start -1.925 -0.825)
			(end -1.625 -0.825)
			(stroke
				(width 0.12)
				(type solid)
			)
			(layer "F.SilkS")
		)
		(fp_rect
			(start -1.9 -1.05)
			(end 1.9 1.05)
			(stroke
				(width 0.05)
				(type solid)
			)
			(fill no)
			(layer "F.CrtYd")
		)
		(fp_rect
			(start -1.601 -0.802)
			(end 1.6 0.8)
			(stroke
				(width 0.1)
				(type solid)
			)
			(fill no)
			(layer "F.Fab")
		)
		(pad "1" smd rect
			(at -1.2 0 180)
			(size 1.2 1.2)
			(layers "F.Cu" "F.Mask" "F.Paste")
			(net 465 "1V0_SYS")
			(pintype "passive")
		)
		(pad "2" smd rect
			(at 1.2 0 180)
			(size 1.2 1.2)
			(layers "F.Cu" "F.Mask" "F.Paste")
			(net 5 "GND")
			(pintype "passive")
		)
	)
)
